# S9S_MB_2U (Grand Teton) — schematic netlist excerpt (pin names and nets, part order shuffled) for the footprints in the layout excerpt that follows; sources: Cadence DE-HDL packaged netlist, KiCad conversion of 03242023_DA0F0TMBIJ0_F0T_Motherboard_J_brd_V01_OCP.brd

R4665  Q_RES  0 5% EMPTY  pkg 0402LF  page 167 : A = P2E_MB_BMC_RX_DP<0> ; B = P2E_MB_BMC_RX_R2_DP<0>
R2507  Q_RES  1K 1% CHIP  pkg 0402LF  page 239 : A = P3V3_AUX ; B = JTAG_BMC_DBP_TDI

(kicad_pcb
	(version 20260206)
	(generator "pcbnew")
	(generator_version "10.0")
	(general
		(thickness 1.6)
		(legacy_teardrops no)
	)
	(paper "A4")
	(title_block
		(title "03242023_DA0F0TMBIJ0_F0T_Motherboard_J_brd_V01_OCP.brd")
		(comment 1 "Grand Teton / footprints 179-180 of 6105")
	)
	(layers
		(0 "F.Cu" signal "TOP")
		(4 "In1.Cu" signal "GND")
		(6 "In2.Cu" signal "IN1")
		(8 "In3.Cu" signal "GND1")
		(10 "In4.Cu" signal "IN2")
		(12 "In5.Cu" signal "GND2")
		(14 "In6.Cu" signal "IN3")
		(16 "In7.Cu" signal "GND3")
		(18 "In8.Cu" signal "VCC")
		(20 "In9.Cu" signal "VCC1")
		(22 "In10.Cu" signal "GND4")
		(24 "In11.Cu" signal "IN4")
		(26 "In12.Cu" signal "GND5")
		(28 "In13.Cu" signal "IN5")
		(30 "In14.Cu" signal "GND6")
		(32 "In15.Cu" signal "IN6")
		(34 "In16.Cu" signal "GND7")
		(2 "B.Cu" signal "BOTTOM")
		(9 "F.Adhes" user "F.Adhesive")
		(11 "B.Adhes" user "B.Adhesive")
		(13 "F.Paste" user "Package Geometry/Pastemask Top")
		(15 "B.Paste" user "Package Geometry/Pastemask Bottom")
		(5 "F.SilkS" user "Ref Des/Silkscreen Top")
		(7 "B.SilkS" user "Ref Des/Silkscreen Bottom")
		(1 "F.Mask" user "Board Geometry/Soldermask Top")
		(3 "B.Mask" user "Board Geometry/Soldermask Bottom")
		(17 "Dwgs.User" user "User.Drawings")
		(19 "Cmts.User" user "User.Comments")
		(21 "Eco1.User" user "User.Eco1")
		(23 "Eco2.User" user "User.Eco2")
		(25 "Edge.Cuts" user "Board Geometry/Outline")
		(27 "Margin" user)
		(31 "F.CrtYd" user "Package Geometry/Place Bound Top")
		(29 "B.CrtYd" user "Package Geometry/Place Bound Bottom")
		(35 "F.Fab" user "Ref Des/Assembly Top")
		(33 "B.Fab" user "Ref Des/Assembly Bottom")
	)
	(footprint ""
		(layer "F.Cu")
		(at 128.778 -73.370948)
		(property "Reference" "R2507"
			(at 0 0 0)
			(layer "F.SilkS")
			(hide yes)
			(effects
				(font
					(size 1.27 1.27)
				)
			)
		)
		(property "Value" ""
			(at 0 0 0)
			(layer "F.Fab")
			(effects
				(font
					(size 1.27 1.27)
				)
			)
		)
		(duplicate_pad_numbers_are_jumpers no)
		(fp_line
			(start -0.7874 -0.4064)
			(end 0.7874 -0.4064)
			(stroke
				(width 0.1524)
				(type default)
			)
			(layer "F.SilkS")
		)
		(fp_line
			(start -0.7874 0.4064)
			(end -0.7874 -0.4064)
			(stroke
				(width 0.1524)
				(type default)
			)
			(layer "F.SilkS")
		)
		(fp_line
			(start 0.7874 -0.4064)
			(end 0.7874 0.4064)
			(stroke
				(width 0.1524)
				(type default)
			)
			(layer "F.SilkS")
		)
		(fp_line
			(start 0.7874 0.4064)
			(end -0.7874 0.4064)
			(stroke
				(width 0.1524)
				(type default)
			)
			(layer "F.SilkS")
		)
		(fp_line
			(start -0.67945 -0.305054)
			(end -0.12065 -0.305054)
			(stroke
				(width 0.1)
				(type default)
			)
			(layer "F.Fab")
		)
		(fp_line
			(start -0.67945 0.3048)
			(end -0.67945 -0.305054)
			(stroke
				(width 0.1)
				(type default)
			)
			(layer "F.Fab")
		)
		(fp_line
			(start -0.12065 -0.305054)
			(end -0.12065 -0.2794)
			(stroke
				(width 0.1)
				(type default)
			)
			(layer "F.Fab")
		)
		(fp_line
			(start -0.12065 -0.2794)
			(end 0.12065 -0.2794)
			(stroke
				(width 0.1)
				(type default)
			)
			(layer "F.Fab")
		)
		(fp_line
			(start -0.12065 0.2794)
			(end -0.12065 0.3048)
			(stroke
				(width 0.1)
				(type default)
			)
			(layer "F.Fab")
		)
		(fp_line
			(start -0.12065 0.3048)
			(end -0.67945 0.3048)
			(stroke
				(width 0.1)
				(type default)
			)
			(layer "F.Fab")
		)
		(fp_line
			(start 0.120396 0.2794)
			(end -0.12065 0.2794)
			(stroke
				(width 0.1)
				(type default)
			)
			(layer "F.Fab")
		)
		(fp_line
			(start 0.120396 0.3048)
			(end 0.120396 0.2794)
			(stroke
				(width 0.1)
				(type default)
			)
			(layer "F.Fab")
		)
		(fp_line
			(start 0.12065 -0.3048)
			(end 0.67945 -0.3048)
			(stroke
				(width 0.1)
				(type default)
			)
			(layer "F.Fab")
		)
		(fp_line
			(start 0.12065 -0.2794)
			(end 0.12065 -0.3048)
			(stroke
				(width 0.1)
				(type default)
			)
			(layer "F.Fab")
		)
		(fp_line
			(start 0.67945 -0.3048)
			(end 0.67945 0.3048)
			(stroke
				(width 0.1)
				(type default)
			)
			(layer "F.Fab")
		)
		(fp_line
			(start 0.67945 0.3048)
			(end 0.120396 0.3048)
			(stroke
				(width 0.1)
				(type default)
			)
			(layer "F.Fab")
		)
		(pad "1" smd circle
			(at -0.40005 0)
			(size 0 0)
			(layers "F.Cu" "F.Mask" "F.Paste")
			(net "P3V3_AUX")
		)
		(pad "2" smd circle
			(at 0.40005 0)
			(size 0 0)
			(layers "F.Cu" "F.Mask" "F.Paste")
			(net "JTAG_BMC_DBP_TDI")
		)
	)
	(footprint ""
		(layer "F.Cu")
		(at 25.9715 -397.688562 90)
		(property "Reference" "R4665"
			(at 0 0 90)
			(layer "F.SilkS")
			(hide yes)
			(effects
				(font
					(size 1.27 1.27)
				)
			)
		)
		(property "Value" ""
			(at 0 0 90)
			(layer "F.Fab")
			(effects
				(font
					(size 1.27 1.27)
				)
			)
		)
		(duplicate_pad_numbers_are_jumpers no)
		(fp_line
			(start -0.013462 -0.4064)
			(end 0.7874 -0.4064)
			(stroke
				(width 0.1524)
				(type default)
			)
			(layer "F.SilkS")
		)
		(fp_line
			(start 0.7874 0.4064)
			(end -0.7874 0.4064)
			(stroke
				(width 0.1524)
				(type default)
			)
			(layer "F.SilkS")
		)
		(fp_line
			(start -0.7874 0.4064)
			(end -0.7874 -0.4064)
			(stroke
				(width 0.1524)
				(type default)
			)
			(layer "F.SilkS")
		)
		(fp_line
			(start -0.12065 -0.305054)
			(end -0.12065 -0.2794)
			(stroke
				(width 0.1)
				(type default)
			)
			(layer "F.Fab")
		)
		(fp_line
			(start -0.67945 -0.305054)
			(end -0.12065 -0.305054)
			(stroke
				(width 0.1)
				(type default)
			)
			(layer "F.Fab")
		)
		(fp_line
			(start 0.67945 -0.3048)
			(end 0.67945 0.3048)
			(stroke
				(width 0.1)
				(type default)
			)
			(layer "F.Fab")
		)
		(fp_line
			(start 0.12065 -0.3048)
			(end 0.67945 -0.3048)
			(stroke
				(width 0.1)
				(type default)
			)
			(layer "F.Fab")
		)
		(fp_line
			(start 0.12065 -0.2794)
			(end 0.12065 -0.3048)
			(stroke
				(width 0.1)
				(type default)
			)
			(layer "F.Fab")
		)
		(fp_line
			(start -0.12065 -0.2794)
			(end 0.12065 -0.2794)
			(stroke
				(width 0.1)
				(type default)
			)
			(layer "F.Fab")
		)
		(fp_line
			(start 0.120396 0.2794)
			(end -0.12065 0.2794)
			(stroke
				(width 0.1)
				(type default)
			)
			(layer "F.Fab")
		)
		(fp_line
			(start -0.12065 0.2794)
			(end -0.12065 0.3048)
			(stroke
				(width 0.1)
				(type default)
			)
			(layer "F.Fab")
		)
		(fp_line
			(start 0.67945 0.3048)
			(end 0.120396 0.3048)
			(stroke
				(width 0.1)
				(type default)
			)
			(layer "F.Fab")
		)
		(fp_line
			(start 0.120396 0.3048)
			(end 0.120396 0.2794)
			(stroke
				(width 0.1)
				(type default)
			)
			(layer "F.Fab")
		)
		(fp_line
			(start -0.12065 0.3048)
			(end -0.67945 0.3048)
			(stroke
				(width 0.1)
				(type default)
			)
			(layer "F.Fab")
		)
		(fp_line
			(start -0.67945 0.3048)
			(end -0.67945 -0.305054)
			(stroke
				(width 0.1)
				(type default)
			)
			(layer "F.Fab")
		)
		(pad "1" smd rect
			(at -0.40005 0 270)
			(size 0.4572 0.508)
			(layers "F.Cu" "F.Mask" "F.Paste")
			(net "P2E_MB_BMC_RX_DP<0>")
		)
		(pad "2" smd rect
			(at 0.40005 0 270)
			(size 0.4572 0.508)
			(layers "F.Cu" "F.Mask" "F.Paste")
			(net "P2E_MB_BMC_RX_R2_DP<0>")
		)
	)
)
